# T6G (Grand Teton) — schematic netlist excerpt (pin names and nets, part order shuffled) for the footprints in the layout excerpt that follows; sources: Cadence DE-HDL packaged netlist, KiCad conversion of 04192023_DAF0TMB3IC0_F0TG_MB_C_brd_V02_OCP.brd

PC122  Q_CAP  0.22UF 16V 10% X7R  pkg 0402  page 202 : A = SW_PVDDCR_CPU1_P0_BOOT3_R ; B = SW_PVDDCR_CPU1_P0_BOOTR3
R4186  Q_RES  1K 1% EMPTY  pkg 0402LF  page 235 : A = P3V3_AUX ; B = U272_2_ADD2

(kicad_pcb
	(version 20260206)
	(generator "pcbnew")
	(generator_version "10.0")
	(general
		(thickness 1.6)
		(legacy_teardrops no)
	)
	(paper "A4")
	(title_block
		(title "04192023_DAF0TMB3IC0_F0TG_MB_C_brd_V02_OCP.brd")
		(comment 1 "Grand Teton / footprints 72-73 of 8354")
	)
	(layers
		(0 "F.Cu" signal "TOP")
		(4 "In1.Cu" signal "GND")
		(6 "In2.Cu" signal "IN1")
		(8 "In3.Cu" signal "GND1")
		(10 "In4.Cu" signal "IN2")
		(12 "In5.Cu" signal "GND2")
		(14 "In6.Cu" signal "IN3")
		(16 "In7.Cu" signal "GND3")
		(18 "In8.Cu" signal "VCC")
		(20 "In9.Cu" signal "VCC1")
		(22 "In10.Cu" signal "GND4")
		(24 "In11.Cu" signal "IN4")
		(26 "In12.Cu" signal "GND5")
		(28 "In13.Cu" signal "IN5")
		(30 "In14.Cu" signal "GND6")
		(32 "In15.Cu" signal "IN6")
		(34 "In16.Cu" signal "GND7")
		(2 "B.Cu" signal "BOTTOM")
		(9 "F.Adhes" user "F.Adhesive")
		(11 "B.Adhes" user "B.Adhesive")
		(13 "F.Paste" user "Package Geometry/Pastemask Top")
		(15 "B.Paste" user "Package Geometry/Pastemask Bottom")
		(5 "F.SilkS" user "Ref Des/Silkscreen Top")
		(7 "B.SilkS" user "Ref Des/Silkscreen Bottom")
		(1 "F.Mask" user "Board Geometry/Soldermask Top")
		(3 "B.Mask" user "Board Geometry/Soldermask Bottom")
		(17 "Dwgs.User" user "User.Drawings")
		(19 "Cmts.User" user "User.Comments")
		(21 "Eco1.User" user "User.Eco1")
		(23 "Eco2.User" user "User.Eco2")
		(25 "Edge.Cuts" user "Board Geometry/Outline")
		(27 "Margin" user)
		(31 "F.CrtYd" user "Package Geometry/Place Bound Top")
		(29 "B.CrtYd" user "Package Geometry/Place Bound Bottom")
		(35 "F.Fab" user "Ref Des/Assembly Top")
		(33 "B.Fab" user "Ref Des/Assembly Bottom")
	)
	(footprint ""
		(layer "F.Cu")
		(at 320.131694 -339.647022 -90)
		(property "Reference" "PC122"
			(at 0 0 270)
			(layer "F.SilkS")
			(hide yes)
			(effects
				(font
					(size 1.27 1.27)
				)
			)
		)
		(property "Value" ""
			(at 0 0 270)
			(layer "F.Fab")
			(effects
				(font
					(size 1.27 1.27)
				)
			)
		)
		(duplicate_pad_numbers_are_jumpers no)
		(fp_line
			(start -0.7874 0.4064)
			(end -0.7874 -0.4064)
			(stroke
				(width 0.1524)
				(type default)
			)
			(layer "F.SilkS")
		)
		(fp_line
			(start 0.7874 0.4064)
			(end -0.7874 0.4064)
			(stroke
				(width 0.1524)
				(type default)
			)
			(layer "F.SilkS")
		)
		(fp_line
			(start -0.7874 -0.4064)
			(end 0.7874 -0.4064)
			(stroke
				(width 0.1524)
				(type default)
			)
			(layer "F.SilkS")
		)
		(fp_line
			(start 0.7874 -0.4064)
			(end 0.7874 0.4064)
			(stroke
				(width 0.1524)
				(type default)
			)
			(layer "F.SilkS")
		)
		(fp_line
			(start -0.67945 0.3048)
			(end -0.67945 -0.305054)
			(stroke
				(width 0.1)
				(type default)
			)
			(layer "F.Fab")
		)
		(fp_line
			(start -0.12065 0.3048)
			(end -0.67945 0.3048)
			(stroke
				(width 0.1)
				(type default)
			)
			(layer "F.Fab")
		)
		(fp_line
			(start 0.120396 0.3048)
			(end 0.120396 0.2794)
			(stroke
				(width 0.1)
				(type default)
			)
			(layer "F.Fab")
		)
		(fp_line
			(start 0.67945 0.3048)
			(end 0.120396 0.3048)
			(stroke
				(width 0.1)
				(type default)
			)
			(layer "F.Fab")
		)
		(fp_line
			(start -0.12065 0.2794)
			(end -0.12065 0.3048)
			(stroke
				(width 0.1)
				(type default)
			)
			(layer "F.Fab")
		)
		(fp_line
			(start 0.120396 0.2794)
			(end -0.12065 0.2794)
			(stroke
				(width 0.1)
				(type default)
			)
			(layer "F.Fab")
		)
		(fp_line
			(start -0.12065 -0.2794)
			(end 0.12065 -0.2794)
			(stroke
				(width 0.1)
				(type default)
			)
			(layer "F.Fab")
		)
		(fp_line
			(start 0.12065 -0.2794)
			(end 0.12065 -0.3048)
			(stroke
				(width 0.1)
				(type default)
			)
			(layer "F.Fab")
		)
		(fp_line
			(start 0.12065 -0.3048)
			(end 0.67945 -0.3048)
			(stroke
				(width 0.1)
				(type default)
			)
			(layer "F.Fab")
		)
		(fp_line
			(start 0.67945 -0.3048)
			(end 0.67945 0.3048)
			(stroke
				(width 0.1)
				(type default)
			)
			(layer "F.Fab")
		)
		(fp_line
			(start -0.67945 -0.305054)
			(end -0.12065 -0.305054)
			(stroke
				(width 0.1)
				(type default)
			)
			(layer "F.Fab")
		)
		(fp_line
			(start -0.12065 -0.305054)
			(end -0.12065 -0.2794)
			(stroke
				(width 0.1)
				(type default)
			)
			(layer "F.Fab")
		)
		(pad "1" smd circle
			(at -0.40005 0 270)
			(size 0 0)
			(layers "F.Cu" "F.Mask" "F.Paste")
			(net "SW_PVDDCR_CPU1_P0_BOOT3_R")
		)
		(pad "2" smd circle
			(at 0.40005 0 270)
			(size 0 0)
			(layers "F.Cu" "F.Mask" "F.Paste")
			(net "SW_PVDDCR_CPU1_P0_BOOTR3")
		)
	)
	(footprint ""
		(layer "F.Cu")
		(at 100.920296 -425.82973 -90)
		(property "Reference" "R4186"
			(at 0 0 270)
			(layer "F.SilkS")
			(hide yes)
			(effects
				(font
					(size 1.27 1.27)
				)
			)
		)
		(property "Value" ""
			(at 0 0 270)
			(layer "F.Fab")
			(effects
				(font
					(size 1.27 1.27)
				)
			)
		)
		(duplicate_pad_numbers_are_jumpers no)
		(fp_line
			(start -0.7874 0.4064)
			(end -0.7874 -0.4064)
			(stroke
				(width 0.1524)
				(type default)
			)
			(layer "F.SilkS")
		)
		(fp_line
			(start 0.7874 0.4064)
			(end -0.7874 0.4064)
			(stroke
				(width 0.1524)
				(type default)
			)
			(layer "F.SilkS")
		)
		(fp_line
			(start -0.7874 -0.4064)
			(end 0.7874 -0.4064)
			(stroke
				(width 0.1524)
				(type default)
			)
			(layer "F.SilkS")
		)
		(fp_line
			(start 0.7874 -0.4064)
			(end 0.7874 0.4064)
			(stroke
				(width 0.1524)
				(type default)
			)
			(layer "F.SilkS")
		)
		(fp_line
			(start -0.67945 0.3048)
			(end -0.67945 -0.305054)
			(stroke
				(width 0.1)
				(type default)
			)
			(layer "F.Fab")
		)
		(fp_line
			(start -0.12065 0.3048)
			(end -0.67945 0.3048)
			(stroke
				(width 0.1)
				(type default)
			)
			(layer "F.Fab")
		)
		(fp_line
			(start 0.120396 0.3048)
			(end 0.120396 0.2794)
			(stroke
				(width 0.1)
				(type default)
			)
			(layer "F.Fab")
		)
		(fp_line
			(start 0.67945 0.3048)
			(end 0.120396 0.3048)
			(stroke
				(width 0.1)
				(type default)
			)
			(layer "F.Fab")
		)
		(fp_line
			(start -0.12065 0.2794)
			(end -0.12065 0.3048)
			(stroke
				(width 0.1)
				(type default)
			)
			(layer "F.Fab")
		)
		(fp_line
			(start 0.120396 0.2794)
			(end -0.12065 0.2794)
			(stroke
				(width 0.1)
				(type default)
			)
			(layer "F.Fab")
		)
		(fp_line
			(start -0.12065 -0.2794)
			(end 0.12065 -0.2794)
			(stroke
				(width 0.1)
				(type default)
			)
			(layer "F.Fab")
		)
		(fp_line
			(start 0.12065 -0.2794)
			(end 0.12065 -0.3048)
			(stroke
				(width 0.1)
				(type default)
			)
			(layer "F.Fab")
		)
		(fp_line
			(start 0.12065 -0.3048)
			(end 0.67945 -0.3048)
			(stroke
				(width 0.1)
				(type default)
			)
			(layer "F.Fab")
		)
		(fp_line
			(start 0.67945 -0.3048)
			(end 0.67945 0.3048)
			(stroke
				(width 0.1)
				(type default)
			)
			(layer "F.Fab")
		)
		(fp_line
			(start -0.67945 -0.305054)
			(end -0.12065 -0.305054)
			(stroke
				(width 0.1)
				(type default)
			)
			(layer "F.Fab")
		)
		(fp_line
			(start -0.12065 -0.305054)
			(end -0.12065 -0.2794)
			(stroke
				(width 0.1)
				(type default)
			)
			(layer "F.Fab")
		)
		(pad "1" smd circle
			(at -0.40005 0 270)
			(size 0 0)
			(layers "F.Cu" "F.Mask" "F.Paste")
			(net "P3V3_AUX")
		)
		(pad "2" smd circle
			(at 0.40005 0 270)
			(size 0 0)
			(layers "F.Cu" "F.Mask" "F.Paste")
			(net "U272_2_ADD2")
		)
	)
)
